(kicad_pcb
	(version 20260206)
	(generator "pcbnew")
	(generator_version "10.0")
	(general
		(thickness 1.6)
		(legacy_teardrops no)
	)
	(paper "A4")
	(title_block
		(title "Bryce Canyon_R.DPB_16317-1_OCP.brd")
		(comment 1 "Bryce Canyon / footprint 518 of 2099 (DPB1), pads 1-73 of 150")
	)
	(layers
		(0 "F.Cu" signal "TOP")
		(4 "In1.Cu" signal "L2GND")
		(6 "In2.Cu" signal "L3")
		(8 "In3.Cu" signal "L4VCC")
		(10 "In4.Cu" signal "L5VCC")
		(12 "In5.Cu" signal "L6")
		(14 "In6.Cu" signal "L7GND")
		(2 "B.Cu" signal "BOTTOM")
		(9 "F.Adhes" user "F.Adhesive")
		(11 "B.Adhes" user "B.Adhesive")
		(13 "F.Paste" user "Package Geometry/Pastemask Top")
		(15 "B.Paste" user "Package Geometry/Pastemask Bottom")
		(5 "F.SilkS" user "Ref Des/Silkscreen Top")
		(7 "B.SilkS" user "Ref Des/Silkscreen Bottom")
		(1 "F.Mask" user "Board Geometry/Soldermask Top")
		(3 "B.Mask" user "Board Geometry/Soldermask Bottom")
		(17 "Dwgs.User" user "User.Drawings")
		(19 "Cmts.User" user "User.Comments")
		(21 "Eco1.User" user "User.Eco1")
		(23 "Eco2.User" user "User.Eco2")
		(25 "Edge.Cuts" user "Board Geometry/Outline")
		(27 "Margin" user)
		(31 "F.CrtYd" user "Package Geometry/Place Bound Top")
		(29 "B.CrtYd" user "Package Geometry/Place Bound Bottom")
		(35 "F.Fab" user "Ref Des/Assembly Top")
		(33 "B.Fab" user "Ref Des/Assembly Bottom")
	)
	(footprint ""
		(layer "F.Cu")
		(at 210.000088 -66.799968)
		(property "Reference" "DPB1"
			(at 0 0 0)
			(layer "F.SilkS")
			(hide yes)
			(effects
				(font
					(size 1.27 1.27)
				)
			)
		)
		(property "Value" "AMP-CONN150-13R-7-GP"
			(at -11.7475 -21.488654 0)
			(unlocked yes)
			(layer "F.Fab")
			(hide yes)
			(effects
				(font
					(size 1.016 1.016)
					(thickness 0.1524)
				)
			)
		)
		(property "Device Type" "PREFIT-150P-234294H542"
			(at -11.7475 -23.012654 0)
			(unlocked yes)
			(layer "F.Fab")
			(hide yes)
			(effects
				(font
					(size 1.016 1.016)
					(thickness 0.1524)
				)
			)
		)
		(duplicate_pad_numbers_are_jumpers no)
		(pad "A1" thru_hole circle
			(at 0 0)
			(size 0.762 0.762)
			(drill 0.359918)
			(layers "*.Cu" "*.Mask")
			(remove_unused_layers no)
			(net "PWM_BMC_B_ZONE_C")
			(clearance 0.1651)
			(thermal_gap 0.1651)
		)
		(pad "A2" thru_hole circle
			(at 1.800098 1.199896)
			(size 0.762 0.762)
			(drill 0.359918)
			(layers "*.Cu" "*.Mask")
			(remove_unused_layers no)
			(net "PCIE_COMP_B_TO_SCC_B_1_DP")
			(clearance 0.1651)
			(thermal_gap 0.1651)
		)
		(pad "A3" thru_hole circle
			(at 3.599942 0)
			(size 0.762 0.762)
			(drill 0.359918)
			(layers "*.Cu" "*.Mask")
			(remove_unused_layers no)
			(net "I2C_DPB_B_SCL")
			(clearance 0.1651)
			(thermal_gap 0.1651)
		)
		(pad "A4" thru_hole circle
			(at 5.40004 1.199896)
			(size 0.762 0.762)
			(drill 0.359918)
			(layers "*.Cu" "*.Mask")
			(remove_unused_layers no)
			(net "PCIE_COMP_B_TO_SCC_B_3_DP")
			(clearance 0.1651)
			(thermal_gap 0.1651)
		)
		(pad "A5" thru_hole circle
			(at 7.199884 0)
			(size 0.762 0.762)
			(drill 0.359918)
			(layers "*.Cu" "*.Mask")
			(remove_unused_layers no)
			(net "I2C_BMC_A_EXP_B_SCL")
			(clearance 0.1651)
			(thermal_gap 0.1651)
		)
		(pad "A6" thru_hole circle
			(at 8.999982 1.199896)
			(size 0.762 0.762)
			(drill 0.359918)
			(layers "*.Cu" "*.Mask")
			(remove_unused_layers no)
			(net "PCIE_COMP_B_TO_SCC_B_5_DP")
			(clearance 0.1651)
			(thermal_gap 0.1651)
		)
		(pad "A7" thru_hole circle
			(at 10.80008 0)
			(size 0.762 0.762)
			(drill 0.359918)
			(layers "*.Cu" "*.Mask")
			(remove_unused_layers no)
			(net "UART_EXP_B_TX")
			(clearance 0.1651)
			(thermal_gap 0.1651)
		)
		(pad "A8" thru_hole circle
			(at 12.599924 1.199896)
			(size 0.762 0.762)
			(drill 0.359918)
			(layers "*.Cu" "*.Mask")
			(remove_unused_layers no)
			(net "PCIE_COMP_B_TO_SCC_B_7_DP")
			(clearance 0.1651)
			(thermal_gap 0.1651)
		)
		(pad "A9" thru_hole circle
			(at 16.20012 0)
			(size 0.762 0.762)
			(drill 0.359918)
			(layers "*.Cu" "*.Mask")
			(remove_unused_layers no)
			(net "SCC_B_STBY_PGOOD")
			(clearance 0.1651)
			(thermal_gap 0.1651)
		)
		(pad "A10" thru_hole circle
			(at 17.999964 2.29997)
			(size 0.762 0.762)
			(drill 0.359918)
			(layers "*.Cu" "*.Mask")
			(remove_unused_layers no)
			(net "SCC_B_PWR_LED")
			(clearance 0.1651)
			(thermal_gap 0.1651)
		)
		(pad "A11" thru_hole circle
			(at 19.800062 0)
			(size 0.762 0.762)
			(drill 0.359918)
			(layers "*.Cu" "*.Mask")
			(remove_unused_layers no)
			(net "DRIVE_B_24_ACT")
			(clearance 0.1651)
			(thermal_gap 0.1651)
		)
		(pad "A12" thru_hole circle
			(at 21.599906 2.29997)
			(size 0.762 0.762)
			(drill 0.359918)
			(layers "*.Cu" "*.Mask")
			(remove_unused_layers no)
			(net "BMC_B_EXP_B_SPARE_0")
			(clearance 0.1651)
			(thermal_gap 0.1651)
		)
		(pad "B1" thru_hole circle
			(at 0 -1.400048)
			(size 0.762 0.762)
			(drill 0.359918)
			(layers "*.Cu" "*.Mask")
			(remove_unused_layers no)
			(net "PWM_BMC_B_ZONE_D")
			(clearance 0.1651)
			(thermal_gap 0.1651)
		)
		(pad "B2" thru_hole circle
			(at 1.800098 -0.199898)
			(size 0.762 0.762)
			(drill 0.359918)
			(layers "*.Cu" "*.Mask")
			(remove_unused_layers no)
			(net "PCIE_COMP_B_TO_SCC_B_1_DN")
			(clearance 0.1651)
			(thermal_gap 0.1651)
		)
		(pad "B3" thru_hole circle
			(at 3.599942 -1.400048)
			(size 0.762 0.762)
			(drill 0.359918)
			(layers "*.Cu" "*.Mask")
			(remove_unused_layers no)
			(net "I2C_DPB_B_SDA")
			(clearance 0.1651)
			(thermal_gap 0.1651)
		)
		(pad "B4" thru_hole circle
			(at 5.40004 -0.199898)
			(size 0.762 0.762)
			(drill 0.359918)
			(layers "*.Cu" "*.Mask")
			(remove_unused_layers no)
			(net "PCIE_COMP_B_TO_SCC_B_3_DN")
			(clearance 0.1651)
			(thermal_gap 0.1651)
		)
		(pad "B5" thru_hole circle
			(at 7.199884 -1.400048)
			(size 0.762 0.762)
			(drill 0.359918)
			(layers "*.Cu" "*.Mask")
			(remove_unused_layers no)
			(net "I2C_BMC_A_EXP_B_SDA")
			(clearance 0.1651)
			(thermal_gap 0.1651)
		)
		(pad "B6" thru_hole circle
			(at 8.999982 -0.199898)
			(size 0.762 0.762)
			(drill 0.359918)
			(layers "*.Cu" "*.Mask")
			(remove_unused_layers no)
			(net "PCIE_COMP_B_TO_SCC_B_5_DN")
			(clearance 0.1651)
			(thermal_gap 0.1651)
		)
		(pad "B7" thru_hole circle
			(at 10.80008 -1.400048)
			(size 0.762 0.762)
			(drill 0.359918)
			(layers "*.Cu" "*.Mask")
			(remove_unused_layers no)
			(net "UART_EXP_B_RX")
			(clearance 0.1651)
			(thermal_gap 0.1651)
		)
		(pad "B8" thru_hole circle
			(at 12.599924 -0.199898)
			(size 0.762 0.762)
			(drill 0.359918)
			(layers "*.Cu" "*.Mask")
			(remove_unused_layers no)
			(net "PCIE_COMP_B_TO_SCC_B_7_DN")
			(clearance 0.1651)
			(thermal_gap 0.1651)
		)
		(pad "B9" thru_hole circle
			(at 16.20012 -1.400048)
			(size 0.762 0.762)
			(drill 0.359918)
			(layers "*.Cu" "*.Mask")
			(remove_unused_layers no)
			(net "SCC_A_FULL_PWR_EN")
			(clearance 0.1651)
			(thermal_gap 0.1651)
		)
		(pad "B10" thru_hole circle
			(at 17.999964 1.199896)
			(size 0.762 0.762)
			(drill 0.359918)
			(layers "*.Cu" "*.Mask")
			(remove_unused_layers no)
			(net "FAN_0_INS_N")
			(clearance 0.1651)
			(thermal_gap 0.1651)
		)
		(pad "B11" thru_hole circle
			(at 19.800062 -1.400048)
			(size 0.762 0.762)
			(drill 0.359918)
			(layers "*.Cu" "*.Mask")
			(remove_unused_layers no)
			(net "DRIVE_B_25_ACT")
			(clearance 0.1651)
			(thermal_gap 0.1651)
		)
		(pad "B12" thru_hole circle
			(at 21.599906 1.199896)
			(size 0.762 0.762)
			(drill 0.359918)
			(layers "*.Cu" "*.Mask")
			(remove_unused_layers no)
			(net "BMC_B_EXP_B_SPARE_1")
			(clearance 0.1651)
			(thermal_gap 0.1651)
		)
		(pad "C1" thru_hole circle
			(at 0 -3.599942)
			(size 0.762 0.762)
			(drill 0.359918)
			(layers "*.Cu" "*.Mask")
			(remove_unused_layers no)
			(net "PCIE_COMP_B_TO_SCC_B_0_DP")
			(clearance 0.1651)
			(thermal_gap 0.1651)
		)
		(pad "C2" thru_hole circle
			(at 1.800098 -2.400046)
			(size 0.762 0.762)
			(drill 0.359918)
			(layers "*.Cu" "*.Mask")
			(remove_unused_layers no)
			(net "I2C_SCC_B_SCL")
			(clearance 0.1651)
			(thermal_gap 0.1651)
		)
		(pad "C3" thru_hole circle
			(at 3.599942 -3.599942)
			(size 0.762 0.762)
			(drill 0.359918)
			(layers "*.Cu" "*.Mask")
			(remove_unused_layers no)
			(net "PCIE_COMP_B_TO_SCC_B_2_DP")
			(clearance 0.1651)
			(thermal_gap 0.1651)
		)
		(pad "C4" thru_hole circle
			(at 5.40004 -2.400046)
			(size 0.762 0.762)
			(drill 0.359918)
			(layers "*.Cu" "*.Mask")
			(remove_unused_layers no)
			(net "PWM_BMC_A_ZONE_C")
			(clearance 0.1651)
			(thermal_gap 0.1651)
		)
		(pad "C5" thru_hole circle
			(at 7.199884 -3.599942)
			(size 0.762 0.762)
			(drill 0.359918)
			(layers "*.Cu" "*.Mask")
			(remove_unused_layers no)
			(net "PCIE_COMP_B_TO_SCC_B_4_DP")
			(clearance 0.1651)
			(thermal_gap 0.1651)
		)
		(pad "C6" thru_hole circle
			(at 8.999982 -2.400046)
			(size 0.762 0.762)
			(drill 0.359918)
			(layers "*.Cu" "*.Mask")
			(remove_unused_layers no)
			(net "I2C_DRIVE_B_FLT_LED_SDA")
			(clearance 0.1651)
			(thermal_gap 0.1651)
		)
		(pad "C7" thru_hole circle
			(at 10.80008 -3.599942)
			(size 0.762 0.762)
			(drill 0.359918)
			(layers "*.Cu" "*.Mask")
			(remove_unused_layers no)
			(net "PCIE_COMP_B_TO_SCC_B_6_DP")
			(clearance 0.1651)
			(thermal_gap 0.1651)
		)
		(pad "C8" thru_hole circle
			(at 12.599924 -2.400046)
			(size 0.762 0.762)
			(drill 0.359918)
			(layers "*.Cu" "*.Mask")
			(remove_unused_layers no)
			(net "UART_IOC_B_TX")
			(clearance 0.1651)
			(thermal_gap 0.1651)
		)
		(pad "C9" thru_hole circle
			(at 16.20012 -2.500122)
			(size 0.762 0.762)
			(drill 0.359918)
			(layers "*.Cu" "*.Mask")
			(remove_unused_layers no)
			(net "SCC_B_FULL_PWR_EN")
			(clearance 0.1651)
			(thermal_gap 0.1651)
		)
		(pad "C10" thru_hole circle
			(at 17.999964 -0.199898)
			(size 0.762 0.762)
			(drill 0.359918)
			(layers "*.Cu" "*.Mask")
			(remove_unused_layers no)
			(net "FAN_1_INS_N")
			(clearance 0.1651)
			(thermal_gap 0.1651)
		)
		(pad "C11" thru_hole circle
			(at 19.800062 -2.500122)
			(size 0.762 0.762)
			(drill 0.359918)
			(layers "*.Cu" "*.Mask")
			(remove_unused_layers no)
			(net "DRIVE_B_26_ACT")
			(clearance 0.1651)
			(thermal_gap 0.1651)
		)
		(pad "C12" thru_hole circle
			(at 21.599906 -0.199898)
			(size 0.762 0.762)
			(drill 0.359918)
			(layers "*.Cu" "*.Mask")
			(remove_unused_layers no)
			(net "BMC_A_HEARTBEAT")
			(clearance 0.1651)
			(thermal_gap 0.1651)
		)
		(pad "D1" thru_hole circle
			(at 0 -4.99999)
			(size 0.762 0.762)
			(drill 0.359918)
			(layers "*.Cu" "*.Mask")
			(remove_unused_layers no)
			(net "PCIE_COMP_B_TO_SCC_B_0_DN")
			(clearance 0.1651)
			(thermal_gap 0.1651)
		)
		(pad "D2" thru_hole circle
			(at 1.800098 -3.800094)
			(size 0.762 0.762)
			(drill 0.359918)
			(layers "*.Cu" "*.Mask")
			(remove_unused_layers no)
			(net "I2C_SCC_B_SDA")
			(clearance 0.1651)
			(thermal_gap 0.1651)
		)
		(pad "D3" thru_hole circle
			(at 3.599942 -4.99999)
			(size 0.762 0.762)
			(drill 0.359918)
			(layers "*.Cu" "*.Mask")
			(remove_unused_layers no)
			(net "PCIE_COMP_B_TO_SCC_B_2_DN")
			(clearance 0.1651)
			(thermal_gap 0.1651)
		)
		(pad "D4" thru_hole circle
			(at 5.40004 -3.800094)
			(size 0.762 0.762)
			(drill 0.359918)
			(layers "*.Cu" "*.Mask")
			(remove_unused_layers no)
			(net "PWM_BMC_A_ZONE_D")
			(clearance 0.1651)
			(thermal_gap 0.1651)
		)
		(pad "D5" thru_hole circle
			(at 7.199884 -4.99999)
			(size 0.762 0.762)
			(drill 0.359918)
			(layers "*.Cu" "*.Mask")
			(remove_unused_layers no)
			(net "PCIE_COMP_B_TO_SCC_B_4_DN")
			(clearance 0.1651)
			(thermal_gap 0.1651)
		)
		(pad "D6" thru_hole circle
			(at 8.999982 -3.800094)
			(size 0.762 0.762)
			(drill 0.359918)
			(layers "*.Cu" "*.Mask")
			(remove_unused_layers no)
			(net "I2C_DRIVE_B_FLT_LED_SCL")
			(clearance 0.1651)
			(thermal_gap 0.1651)
		)
		(pad "D7" thru_hole circle
			(at 10.80008 -4.99999)
			(size 0.762 0.762)
			(drill 0.359918)
			(layers "*.Cu" "*.Mask")
			(remove_unused_layers no)
			(net "PCIE_COMP_B_TO_SCC_B_6_DN")
			(clearance 0.1651)
			(thermal_gap 0.1651)
		)
		(pad "D8" thru_hole circle
			(at 12.599924 -3.800094)
			(size 0.762 0.762)
			(drill 0.359918)
			(layers "*.Cu" "*.Mask")
			(remove_unused_layers no)
			(net "UART_IOC_B_RX")
			(clearance 0.1651)
			(thermal_gap 0.1651)
		)
		(pad "D9" thru_hole circle
			(at 16.20012 -3.599942)
			(size 0.762 0.762)
			(drill 0.359918)
			(layers "*.Cu" "*.Mask")
			(remove_unused_layers no)
			(net "SCC_B_FULL_PGOOD")
			(clearance 0.1651)
			(thermal_gap 0.1651)
		)
		(pad "D10" thru_hole circle
			(at 17.999964 -1.299972)
			(size 0.762 0.762)
			(drill 0.359918)
			(layers "*.Cu" "*.Mask")
			(remove_unused_layers no)
			(net "FAN_2_INS_N")
			(clearance 0.1651)
			(thermal_gap 0.1651)
		)
		(pad "D11" thru_hole circle
			(at 19.800062 -3.599942)
			(size 0.762 0.762)
			(drill 0.359918)
			(layers "*.Cu" "*.Mask")
			(remove_unused_layers no)
			(net "DRIVE_B_27_ACT")
			(clearance 0.1651)
			(thermal_gap 0.1651)
		)
		(pad "D12" thru_hole circle
			(at 21.599906 -1.299972)
			(size 0.762 0.762)
			(drill 0.359918)
			(layers "*.Cu" "*.Mask")
			(remove_unused_layers no)
			(net "BMC_B_HEARTBEAT")
			(clearance 0.1651)
			(thermal_gap 0.1651)
		)
		(pad "E1" thru_hole circle
			(at 0 -7.199884)
			(size 0.762 0.762)
			(drill 0.359918)
			(layers "*.Cu" "*.Mask")
			(remove_unused_layers no)
			(net "PCIE_COMP_B_TO_SCC_B_CLK_0_DP")
			(clearance 0.1651)
			(thermal_gap 0.1651)
		)
		(pad "E2" thru_hole circle
			(at 1.800098 -5.999988)
			(size 0.762 0.762)
			(drill 0.359918)
			(layers "*.Cu" "*.Mask")
			(remove_unused_layers no)
			(net "I2C_DPB_A_SCL_BUF")
			(clearance 0.1651)
			(thermal_gap 0.1651)
		)
		(pad "E3" thru_hole circle
			(at 3.599942 -7.199884)
			(size 0.762 0.762)
			(drill 0.359918)
			(layers "*.Cu" "*.Mask")
			(remove_unused_layers no)
			(net "I2C_CLIP_A_SCL")
			(clearance 0.1651)
			(thermal_gap 0.1651)
		)
		(pad "E4" thru_hole circle
			(at 5.40004 -5.999988)
			(size 0.762 0.762)
			(drill 0.359918)
			(layers "*.Cu" "*.Mask")
			(remove_unused_layers no)
			(net "COMP_B_EXP_B_SPARE_0")
			(clearance 0.1651)
			(thermal_gap 0.1651)
		)
		(pad "E5" thru_hole circle
			(at 7.199884 -7.199884)
			(size 0.762 0.762)
			(drill 0.359918)
			(layers "*.Cu" "*.Mask")
			(remove_unused_layers no)
			(net "I2C_BMC_B_EXP_B_SCL")
			(clearance 0.1651)
			(thermal_gap 0.1651)
		)
		(pad "E6" thru_hole circle
			(at 8.999982 -5.999988)
			(size 0.762 0.762)
			(drill 0.359918)
			(layers "*.Cu" "*.Mask")
			(remove_unused_layers no)
			(net "Net_76")
			(clearance 0.1651)
			(thermal_gap 0.1651)
		)
		(pad "E7" thru_hole circle
			(at 10.80008 -7.199884)
			(size 0.762 0.762)
			(drill 0.359918)
			(layers "*.Cu" "*.Mask")
			(remove_unused_layers no)
			(net "UART_SDB_B_RX")
			(clearance 0.1651)
			(thermal_gap 0.1651)
		)
		(pad "E8" thru_hole circle
			(at 12.599924 -5.999988)
			(size 0.762 0.762)
			(drill 0.359918)
			(layers "*.Cu" "*.Mask")
			(remove_unused_layers no)
			(net "PWM_SCC_A_ZONE_C")
			(clearance 0.1651)
			(thermal_gap 0.1651)
		)
		(pad "E9" thru_hole circle
			(at 16.20012 -4.99999)
			(size 0.762 0.762)
			(drill 0.359918)
			(layers "*.Cu" "*.Mask")
			(remove_unused_layers no)
			(net "DRAWER_CLOSED_N")
			(clearance 0.1651)
			(thermal_gap 0.1651)
		)
		(pad "E10" thru_hole circle
			(at 17.999964 -2.400046)
			(size 0.762 0.762)
			(drill 0.359918)
			(layers "*.Cu" "*.Mask")
			(remove_unused_layers no)
			(net "FAN_3_INS_N")
			(clearance 0.1651)
			(thermal_gap 0.1651)
		)
		(pad "E11" thru_hole circle
			(at 19.800062 -4.99999)
			(size 0.762 0.762)
			(drill 0.359918)
			(layers "*.Cu" "*.Mask")
			(remove_unused_layers no)
			(net "DRIVE_B_28_ACT")
			(clearance 0.1651)
			(thermal_gap 0.1651)
		)
		(pad "E12" thru_hole circle
			(at 21.599906 -2.400046)
			(size 0.762 0.762)
			(drill 0.359918)
			(layers "*.Cu" "*.Mask")
			(remove_unused_layers no)
			(net "SCC_A_HEARTBEAT")
			(clearance 0.1651)
			(thermal_gap 0.1651)
		)
		(pad "F1" thru_hole circle
			(at 0 -8.599932)
			(size 0.762 0.762)
			(drill 0.359918)
			(layers "*.Cu" "*.Mask")
			(remove_unused_layers no)
			(net "PCIE_COMP_B_TO_SCC_B_CLK_0_DN")
			(clearance 0.1651)
			(thermal_gap 0.1651)
		)
		(pad "F2" thru_hole circle
			(at 1.800098 -7.400036)
			(size 0.762 0.762)
			(drill 0.359918)
			(layers "*.Cu" "*.Mask")
			(remove_unused_layers no)
			(net "I2C_DPB_A_SDA_BUF")
			(clearance 0.1651)
			(thermal_gap 0.1651)
		)
		(pad "F3" thru_hole circle
			(at 3.599942 -8.599932)
			(size 0.762 0.762)
			(drill 0.359918)
			(layers "*.Cu" "*.Mask")
			(remove_unused_layers no)
			(net "I2C_CLIP_A_SDA")
			(clearance 0.1651)
			(thermal_gap 0.1651)
		)
		(pad "F4" thru_hole circle
			(at 5.40004 -7.400036)
			(size 0.762 0.762)
			(drill 0.359918)
			(layers "*.Cu" "*.Mask")
			(remove_unused_layers no)
			(net "PCIE_COMP_B_TO_SCC_B_RST_0")
			(clearance 0.1651)
			(thermal_gap 0.1651)
		)
		(pad "F5" thru_hole circle
			(at 7.199884 -8.599932)
			(size 0.762 0.762)
			(drill 0.359918)
			(layers "*.Cu" "*.Mask")
			(remove_unused_layers no)
			(net "I2C_BMC_B_EXP_B_SDA")
			(clearance 0.1651)
			(thermal_gap 0.1651)
		)
		(pad "F6" thru_hole circle
			(at 8.999982 -7.400036)
			(size 0.762 0.762)
			(drill 0.359918)
			(layers "*.Cu" "*.Mask")
			(remove_unused_layers no)
			(net "SCC_B_RESET_N")
			(clearance 0.1651)
			(thermal_gap 0.1651)
		)
		(pad "F7" thru_hole circle
			(at 10.80008 -8.599932)
			(size 0.762 0.762)
			(drill 0.359918)
			(layers "*.Cu" "*.Mask")
			(remove_unused_layers no)
			(net "UART_SDB_B_TX")
			(clearance 0.1651)
			(thermal_gap 0.1651)
		)
		(pad "F8" thru_hole circle
			(at 12.599924 -7.400036)
			(size 0.762 0.762)
			(drill 0.359918)
			(layers "*.Cu" "*.Mask")
			(remove_unused_layers no)
			(net "PWM_SCC_A_ZONE_D")
			(clearance 0.1651)
			(thermal_gap 0.1651)
		)
		(pad "F9" thru_hole circle
			(at 16.20012 -6.100064)
			(size 0.762 0.762)
			(drill 0.359918)
			(layers "*.Cu" "*.Mask")
			(remove_unused_layers no)
			(net "P12V_IN_PGOOD")
			(clearance 0.1651)
			(thermal_gap 0.1651)
		)
		(pad "F10" thru_hole circle
			(at 17.999964 -3.800094)
			(size 0.762 0.762)
			(drill 0.359918)
			(layers "*.Cu" "*.Mask")
			(remove_unused_layers no)
			(net "IOM_A_INS_N")
			(clearance 0.1651)
			(thermal_gap 0.1651)
		)
		(pad "F11" thru_hole circle
			(at 19.800062 -6.100064)
			(size 0.762 0.762)
			(drill 0.359918)
			(layers "*.Cu" "*.Mask")
			(remove_unused_layers no)
			(net "DRIVE_B_29_ACT")
			(clearance 0.1651)
			(thermal_gap 0.1651)
		)
		(pad "F12" thru_hole circle
			(at 21.599906 -3.800094)
			(size 0.762 0.762)
			(drill 0.359918)
			(layers "*.Cu" "*.Mask")
			(remove_unused_layers no)
			(net "SCC_B_HEARTBEAT")
			(clearance 0.1651)
			(thermal_gap 0.1651)
		)
		(pad "G1" thru_hole circle
			(at 0 -10.80008)
			(size 0.762 0.762)
			(drill 0.359918)
			(layers "*.Cu" "*.Mask")
			(remove_unused_layers no)
			(net "PCIE_SCC_B_TO_COMP_B_0_DP")
			(clearance 0.1651)
			(thermal_gap 0.1651)
		)
	)
)
